(kicad_pcb
	(version 20221018)
	(generator pcbnew)
	(general
    (thickness 0.908)
  )
	(paper "A4")
	(title_block
    (title "HDMI-MIPI Bridge")
    (date "2024-04-24")
    (rev "1.3.2")
		(comment 9 "footprints 116-121 of 121")
	)
	(layers
    (0 "F.Cu" signal)
    (1 "In1.Cu" signal)
    (2 "In2.Cu" signal)
    (31 "B.Cu" signal)
    (32 "B.Adhes" user "B.Adhesive")
    (33 "F.Adhes" user "F.Adhesive")
    (34 "B.Paste" user)
    (35 "F.Paste" user)
    (36 "B.SilkS" user "B.Silkscreen")
    (37 "F.SilkS" user "F.Silkscreen")
    (38 "B.Mask" user)
    (39 "F.Mask" user)
    (40 "Dwgs.User" user "User.Drawings")
    (41 "Cmts.User" user "User.Comments")
    (42 "Eco1.User" user "User.Eco1")
    (43 "Eco2.User" user "User.Eco2")
    (44 "Edge.Cuts" user)
    (45 "Margin" user)
    (46 "B.CrtYd" user "B.Courtyard")
    (47 "F.CrtYd" user "F.Courtyard")
    (48 "B.Fab" user)
    (49 "F.Fab" user)
  )
	(footprint "antmicro-footprints:Spacer_Drill3.7mm_H6mm_9774060151R" (layer "B.Cu")
    (at 119 131 180)
    (property "Author" "Antmicro")
    (property "License" "Apache-2.0")
    (property "MPN" "9774060151R")
    (property "Manufacturer" "Würth Elektronik")
    (property "Public" "False")
    (property "Sheetfile" "csi.kicad_sch")
    (property "Sheetname" "CSI")
    (property "ki_description" "Spacer, SMT, Non Stop, Steel, Swage Round, 5.1 mm x 6 mm, M2.5 Thread, WA-SMSI Series")
    (property "ki_keywords" "MECHANICAL, SPACER")
    (attr smd)
    (fp_text reference "SP4" (at 0 3.2) (layer "B.SilkS") hide
        (effects (font (size 0.7 0.7) (thickness 0.15)) (justify left bottom mirror))
    )
    (fp_text value "Spacer_Drill3.7mm_H6mm_9774060151R" (at 0 -4) (layer "B.Fab")
        (effects (font (size 0.7 0.7) (thickness 0.15)) (justify left bottom mirror))
    )
    (fp_text user "Author: Antmicro" (at -2.551 -6.5) (layer "B.Fab") hide
        (effects (font (size 0.7 0.7) (thickness 0.15)) (justify left bottom mirror))
    )
    (fp_text user "License: Apache-2.0" (at -2.551 -7.75) (layer "B.Fab") hide
        (effects (font (size 0.7 0.7) (thickness 0.15)) (justify left bottom mirror))
    )
    (fp_text user "${REFERENCE}" (at -2.551 -5.25) (layer "B.Fab") hide
        (effects (font (size 0.7 0.7) (thickness 0.15)) (justify left bottom mirror))
    )
    (fp_circle (center 0 0) (end 3.05 0)
      (stroke (width 0.05) (type solid)) (fill none) (layer "B.CrtYd"))
    (fp_circle (center -0.001 0) (end 2.548 0)
      (stroke (width 0.15) (type solid)) (fill none) (layer "B.Fab"))
    (pad "" smd custom (at -1.71 -1.699 90) (size 0.62 0.62) (layers "B.Paste")
      (thermal_bridge_angle 90)
      (options (clearance outline) (anchor circle))
      (primitives
        (gr_arc (start 1.266786 0.24747) (mid 0.285453 -0.29439) (end -0.250195 -1.279127) (width 0.2))
        (gr_arc (start 1.259603 0.339191) (mid 0.218448 -0.232561) (end -0.34334 -1.279127) (width 0.2))
        (gr_arc (start 1.255279 0.431435) (mid 0.152481 -0.169693) (end -0.436309 -1.279127) (width 0.2))
        (gr_arc (start 1.253811 0.524161) (mid 0.087542 -0.105784) (end -0.529126 -1.279127) (width 0.2))
        (gr_arc (start 1.275473 0.621136) (mid 0.0309 -0.033527) (end -0.621807 -1.279127) (width 0.2))
        (gr_arc (start 1.263664 0.711602) (mid -0.037759 0.026651) (end -0.71437 -1.279127) (width 0.2))
        (gr_arc (start 1.253435 0.802342) (mid -0.105837 0.087395) (end -0.806826 -1.279127) (width 0.2))
        (gr_arc (start 1.267475 0.897258) (mid -0.165236 0.156885) (end -0.899187 -1.279127) (width 0.2))
        (gr_arc (start 1.270645 0.990112) (mid -0.228522 0.222449) (end -0.991463 -1.279127) (width 0.2))
        (gr_arc (start 1.266278 1.081674) (mid -0.294507 0.285313) (end -1.083663 -1.279127) (width 0.2))
        (gr_line (start 1.279127 1.083663) (end 1.279127 0.250195) (width 0.2))
        (gr_line (start -1.083663 -1.279127) (end -0.250195 -1.279127) (width 0.2))
      ))
    (pad "" smd custom (at -1.71 1.71 180) (size 0.62 0.62) (layers "B.Paste")
      (thermal_bridge_angle 90)
      (options (clearance outline) (anchor circle))
      (primitives
        (gr_arc (start 1.266786 0.24747) (mid 0.285453 -0.29439) (end -0.250195 -1.279127) (width 0.2))
        (gr_arc (start 1.259603 0.339191) (mid 0.218448 -0.232561) (end -0.34334 -1.279127) (width 0.2))
        (gr_arc (start 1.255279 0.431435) (mid 0.152481 -0.169693) (end -0.436309 -1.279127) (width 0.2))
        (gr_arc (start 1.253811 0.524161) (mid 0.087542 -0.105784) (end -0.529126 -1.279127) (width 0.2))
        (gr_arc (start 1.275473 0.621136) (mid 0.0309 -0.033527) (end -0.621807 -1.279127) (width 0.2))
        (gr_arc (start 1.263664 0.711602) (mid -0.037759 0.026651) (end -0.71437 -1.279127) (width 0.2))
        (gr_arc (start 1.253435 0.802342) (mid -0.105837 0.087395) (end -0.806826 -1.279127) (width 0.2))
        (gr_arc (start 1.267475 0.897258) (mid -0.165236 0.156885) (end -0.899187 -1.279127) (width 0.2))
        (gr_arc (start 1.270645 0.990112) (mid -0.228522 0.222449) (end -0.991463 -1.279127) (width 0.2))
        (gr_arc (start 1.266278 1.081674) (mid -0.294507 0.285313) (end -1.083663 -1.279127) (width 0.2))
        (gr_line (start 1.279127 1.083663) (end 1.279127 0.250195) (width 0.2))
        (gr_line (start -1.083663 -1.279127) (end -0.250195 -1.279127) (width 0.2))
      ))
    (pad "" smd custom (at 1.699 -1.699) (size 0.62 0.62) (layers "B.Paste")
      (thermal_bridge_angle 90)
      (options (clearance outline) (anchor circle))
      (primitives
        (gr_arc (start 1.266786 0.24747) (mid 0.285453 -0.29439) (end -0.250195 -1.279127) (width 0.2))
        (gr_arc (start 1.259603 0.339191) (mid 0.218448 -0.232561) (end -0.34334 -1.279127) (width 0.2))
        (gr_arc (start 1.255279 0.431435) (mid 0.152481 -0.169693) (end -0.436309 -1.279127) (width 0.2))
        (gr_arc (start 1.253811 0.524161) (mid 0.087542 -0.105784) (end -0.529126 -1.279127) (width 0.2))
        (gr_arc (start 1.275473 0.621136) (mid 0.0309 -0.033527) (end -0.621807 -1.279127) (width 0.2))
        (gr_arc (start 1.263664 0.711602) (mid -0.037759 0.026651) (end -0.71437 -1.279127) (width 0.2))
        (gr_arc (start 1.253435 0.802342) (mid -0.105837 0.087395) (end -0.806826 -1.279127) (width 0.2))
        (gr_arc (start 1.267475 0.897258) (mid -0.165236 0.156885) (end -0.899187 -1.279127) (width 0.2))
        (gr_arc (start 1.270645 0.990112) (mid -0.228522 0.222449) (end -0.991463 -1.279127) (width 0.2))
        (gr_arc (start 1.266278 1.081674) (mid -0.294507 0.285313) (end -1.083663 -1.279127) (width 0.2))
        (gr_line (start 1.279127 1.083663) (end 1.279127 0.250195) (width 0.2))
        (gr_line (start -1.083663 -1.279127) (end -0.250195 -1.279127) (width 0.2))
      ))
    (pad "" smd custom (at 1.699 1.71 270) (size 0.62 0.62) (layers "B.Paste")
      (thermal_bridge_angle 90)
      (options (clearance outline) (anchor circle))
      (primitives
        (gr_arc (start 1.266786 0.24747) (mid 0.285453 -0.29439) (end -0.250195 -1.279127) (width 0.2))
        (gr_arc (start 1.259603 0.339191) (mid 0.218448 -0.232561) (end -0.34334 -1.279127) (width 0.2))
        (gr_arc (start 1.255279 0.431435) (mid 0.152481 -0.169693) (end -0.436309 -1.279127) (width 0.2))
        (gr_arc (start 1.253811 0.524161) (mid 0.087542 -0.105784) (end -0.529126 -1.279127) (width 0.2))
        (gr_arc (start 1.275473 0.621136) (mid 0.0309 -0.033527) (end -0.621807 -1.279127) (width 0.2))
        (gr_arc (start 1.263664 0.711602) (mid -0.037759 0.026651) (end -0.71437 -1.279127) (width 0.2))
        (gr_arc (start 1.253435 0.802342) (mid -0.105837 0.087395) (end -0.806826 -1.279127) (width 0.2))
        (gr_arc (start 1.267475 0.897258) (mid -0.165236 0.156885) (end -0.899187 -1.279127) (width 0.2))
        (gr_arc (start 1.270645 0.990112) (mid -0.228522 0.222449) (end -0.991463 -1.279127) (width 0.2))
        (gr_arc (start 1.266278 1.081674) (mid -0.294507 0.285313) (end -1.083663 -1.279127) (width 0.2))
        (gr_line (start 1.279127 1.083663) (end 1.279127 0.250195) (width 0.2))
        (gr_line (start -1.083663 -1.279127) (end -0.250195 -1.279127) (width 0.2))
      ))
    (pad "1" thru_hole circle (at -0.001 0 180) (size 6 6) (drill 3.7) (layers "*.Cu" "*.Mask")
      (net 2 "GND") (pintype "passive") (solder_paste_margin_ratio -0.05))
  )
	(footprint "antmicro-footprints:TP_SMD_0.75mm" (layer "B.Cu")
    (at 155.4 115.0508 180)
    (property "Author" "Antmicro")
    (property "License" "Apache-2.0")
    (property "MPN" "")
    (property "Manufacturer" "")
    (property "Public" "False")
    (property "Sheetfile" "channel2.kicad_sch")
    (property "Sheetname" "Channel 2")
    (property "exclude_from_bom" "")
    (property "ki_description" "SMT test point")
    (property "ki_keywords" "TESTPOINT")
    (attr exclude_from_pos_files exclude_from_bom)
    (fp_text reference "TP6" (at -2.65 -0.3692) (layer "B.SilkS")
        (effects (font (size 0.65 0.65) (thickness 0.13)) (justify left bottom mirror))
    )
    (fp_text value "TP_0.75mm_SMD" (at 0 -1.2) (layer "B.Fab")
        (effects (font (size 0.65 0.65) (thickness 0.13)) (justify left bottom mirror))
    )
    (fp_text user "${REFERENCE}" (at -0.4 -2.7) (layer "B.Fab") hide
        (effects (font (size 0.7 0.7) (thickness 0.15)) (justify left bottom mirror))
    )
    (fp_text user "Author: Antmicro" (at -0.4 -3.901) (layer "B.Fab") hide
        (effects (font (size 0.7 0.7) (thickness 0.15)) (justify left bottom mirror))
    )
    (fp_text user "License: Apache-2.0" (at -0.4 -5.101) (layer "B.Fab") hide
        (effects (font (size 0.7 0.7) (thickness 0.15)) (justify left bottom mirror))
    )
    (pad "1" smd circle (at 0 0 180) (size 0.75 0.75) (layers "B.Cu" "B.Mask")
      (net 121 "Net-(U4A-EDID_SCL)") (pinfunction "1") (pintype "passive"))
  )
	(footprint "antmicro-footprints:R_0603_1608Metric" (layer "B.Cu")
    (at 130.8 109.4 180)
    (descr "Resistor SMD 0603")
    (tags "resistor SMD 0603")
    (property "Author" "Antmicro")
    (property "Current" "1A")
    (property "License" "Apache-2.0")
    (property "MPN" "CR0603-J/-000ELF")
    (property "Manufacturer" "Bourns")
    (property "Public" "False")
    (property "Sheetfile" "channel1.kicad_sch")
    (property "Sheetname" "Channel 1")
    (property "Tolerance" "")
    (property "Val" "0R")
    (property "ki_description" "Zero Ohm Resistor, Jumper, 0603 [1608 Metric], Thick Film, 100 mW, 1 A, Surface Mount Device, CR")
    (property "ki_keywords" "0603, SMT, RESISTOR, PASSIVE")
    (attr smd)
    (fp_text reference "R8" (at 1 -0.4) (layer "B.SilkS")
        (effects (font (size 0.7 0.7) (thickness 0.15)) (justify left bottom mirror))
    )
    (fp_text value "R_0R_0603" (at 0 -1.6) (layer "B.Fab")
        (effects (font (size 0.7 0.7) (thickness 0.15)) (justify left bottom mirror))
    )
    (fp_text user "License: Apache-2.0" (at -1.25 -5.9) (layer "B.Fab") hide
        (effects (font (size 0.7 0.7) (thickness 0.15)) (justify left bottom mirror))
    )
    (fp_text user "Author: Antmicro" (at -1.25 -4.9) (layer "B.Fab") hide
        (effects (font (size 0.7 0.7) (thickness 0.15)) (justify left bottom mirror))
    )
    (fp_text user "${REFERENCE}" (at -1.25 -3.898) (layer "B.Fab") hide
        (effects (font (size 0.7 0.7) (thickness 0.15)) (justify left bottom mirror))
    )
    (fp_line (start -0.15 -0.4) (end 0.15 -0.4)
      (stroke (width 0.15) (type solid)) (layer "B.SilkS"))
    (fp_line (start -0.15 0.4) (end 0.15 0.4)
      (stroke (width 0.15) (type solid)) (layer "B.SilkS"))
    (fp_rect (start -1.25 0.65) (end 1.25 -0.65)
      (stroke (width 0.05) (type solid)) (fill none) (layer "B.CrtYd"))
    (fp_rect (start -0.8 0.4) (end 0.8 -0.4)
      (stroke (width 0.15) (type solid)) (fill none) (layer "B.Fab"))
    (pad "1" smd roundrect (at -0.7 0 180) (size 0.8 1) (layers "B.Cu" "B.Paste" "B.Mask") (roundrect_rratio 0.2)
      (net 100 "/Channel 1/CH1_AVDD33") (pintype "passive"))
    (pad "2" smd roundrect (at 0.7 0 180) (size 0.8 1) (layers "B.Cu" "B.Paste" "B.Mask") (roundrect_rratio 0.2)
      (net 9 "+3V3") (pintype "passive"))
  )
	(footprint "antmicro-footprints:TP_SMD_0.75mm" (layer "B.Cu")
    (at 143.7 102.4008 180)
    (property "Author" "Antmicro")
    (property "License" "Apache-2.0")
    (property "MPN" "")
    (property "Manufacturer" "")
    (property "Public" "False")
    (property "Sheetfile" "channel1.kicad_sch")
    (property "Sheetname" "Channel 1")
    (property "exclude_from_bom" "")
    (property "ki_description" "SMT test point")
    (property "ki_keywords" "TESTPOINT")
    (attr exclude_from_pos_files exclude_from_bom)
    (fp_text reference "TP4" (at 0 0.6) (layer "B.SilkS")
        (effects (font (size 0.65 0.65) (thickness 0.13)) (justify left bottom mirror))
    )
    (fp_text value "TP_0.75mm_SMD" (at 0 -1.2) (layer "B.Fab")
        (effects (font (size 0.65 0.65) (thickness 0.13)) (justify left bottom mirror))
    )
    (fp_text user "${REFERENCE}" (at -0.4 -2.7) (layer "B.Fab") hide
        (effects (font (size 0.7 0.7) (thickness 0.15)) (justify left bottom mirror))
    )
    (fp_text user "Author: Antmicro" (at -0.4 -3.901) (layer "B.Fab") hide
        (effects (font (size 0.7 0.7) (thickness 0.15)) (justify left bottom mirror))
    )
    (fp_text user "License: Apache-2.0" (at -0.4 -5.101) (layer "B.Fab") hide
        (effects (font (size 0.7 0.7) (thickness 0.15)) (justify left bottom mirror))
    )
    (pad "1" smd circle (at 0 0 180) (size 0.75 0.75) (layers "B.Cu" "B.Mask")
      (net 118 "Net-(U3-EN)") (pinfunction "1") (pintype "passive"))
  )
	(footprint "antmicro-footprints:R_0603_1608Metric" (layer "B.Cu")
    (at 154.8 109.45 180)
    (descr "Resistor SMD 0603")
    (tags "resistor SMD 0603")
    (property "Author" "Antmicro")
    (property "Current" "1A")
    (property "License" "Apache-2.0")
    (property "MPN" "CR0603-J/-000ELF")
    (property "Manufacturer" "Bourns")
    (property "Public" "False")
    (property "Sheetfile" "channel2.kicad_sch")
    (property "Sheetname" "Channel 2")
    (property "Tolerance" "")
    (property "Val" "0R")
    (property "ki_description" "Zero Ohm Resistor, Jumper, 0603 [1608 Metric], Thick Film, 100 mW, 1 A, Surface Mount Device, CR")
    (property "ki_keywords" "0603, SMT, RESISTOR, PASSIVE")
    (attr smd)
    (fp_text reference "R21" (at 1 -0.35) (layer "B.SilkS")
        (effects (font (size 0.7 0.7) (thickness 0.15)) (justify left bottom mirror))
    )
    (fp_text value "R_0R_0603" (at 0 -1.6) (layer "B.Fab")
        (effects (font (size 0.7 0.7) (thickness 0.15)) (justify left bottom mirror))
    )
    (fp_text user "${REFERENCE}" (at -1.25 -3.898) (layer "B.Fab") hide
        (effects (font (size 0.7 0.7) (thickness 0.15)) (justify left bottom mirror))
    )
    (fp_text user "License: Apache-2.0" (at -1.25 -5.9) (layer "B.Fab") hide
        (effects (font (size 0.7 0.7) (thickness 0.15)) (justify left bottom mirror))
    )
    (fp_text user "Author: Antmicro" (at -1.25 -4.9) (layer "B.Fab") hide
        (effects (font (size 0.7 0.7) (thickness 0.15)) (justify left bottom mirror))
    )
    (fp_line (start -0.15 -0.4) (end 0.15 -0.4)
      (stroke (width 0.15) (type solid)) (layer "B.SilkS"))
    (fp_line (start -0.15 0.4) (end 0.15 0.4)
      (stroke (width 0.15) (type solid)) (layer "B.SilkS"))
    (fp_rect (start -1.25 0.65) (end 1.25 -0.65)
      (stroke (width 0.05) (type solid)) (fill none) (layer "B.CrtYd"))
    (fp_rect (start -0.8 0.4) (end 0.8 -0.4)
      (stroke (width 0.15) (type solid)) (fill none) (layer "B.Fab"))
    (pad "1" smd roundrect (at -0.7 0 180) (size 0.8 1) (layers "B.Cu" "B.Paste" "B.Mask") (roundrect_rratio 0.2)
      (net 108 "/Channel 2/CH2_AVDD33") (pintype "passive"))
    (pad "2" smd roundrect (at 0.7 0 180) (size 0.8 1) (layers "B.Cu" "B.Paste" "B.Mask") (roundrect_rratio 0.2)
      (net 9 "+3V3") (pintype "passive"))
  )
	(footprint "antmicro-footprints:C_0402_1005Metric" (layer "B.Cu")
    (at 163.8 110.15 180)
    (descr "Capacitor SMD 0402")
    (tags "capacitor SMD 0402")
    (property "Author" "Antmicro")
    (property "Dielectric" "X5R")
    (property "License" "Apache-2.0")
    (property "MPN" "GRM155R61H104KE14D")
    (property "Manufacturer" "Murata")
    (property "Public" "False")
    (property "Sheetfile" "channel2.kicad_sch")
    (property "Sheetname" "Channel 2")
    (property "Val" "100n")
    (property "Voltage" "50V")
    (property "ki_description" "SMD Multilayer Ceramic Capacitor, 0.1 µF, 50 V, 0402 [1005 Metric], ± 10%, X5R, GRM Series")
    (property "ki_keywords" "0402, SMT, CAPACITOR, PASSIVE, CERAMIC, MLCC")
    (attr smd)
    (fp_text reference "C26" (at 0.9 -0.3) (layer "B.SilkS")
        (effects (font (size 0.65 0.65) (thickness 0.13)) (justify left bottom mirror))
    )
    (fp_text value "C_100n_0402" (at 0 -1.4) (layer "B.Fab")
        (effects (font (size 0.65 0.65) (thickness 0.13)) (justify left bottom mirror))
    )
    (fp_text user "${REFERENCE}" (at -0.932 -3.168) (layer "B.Fab") hide
        (effects (font (size 0.7 0.7) (thickness 0.15)) (justify left bottom mirror))
    )
    (fp_text user "Author: Antmicro" (at -0.932 -4.17) (layer "B.Fab") hide
        (effects (font (size 0.7 0.7) (thickness 0.15)) (justify left bottom mirror))
    )
    (fp_text user "License: Apache-2.0" (at -0.932 -5.17) (layer "B.Fab") hide
        (effects (font (size 0.7 0.7) (thickness 0.15)) (justify left bottom mirror))
    )
    (fp_rect (start -0.925 0.47) (end 0.925 -0.47)
      (stroke (width 0.05) (type default)) (fill none) (layer "B.CrtYd"))
    (fp_line (start -0.494 -0.248) (end -0.494 0.25)
      (stroke (width 0.15) (type solid)) (layer "B.Fab"))
    (fp_line (start -0.494 0.25) (end 0.504 0.25)
      (stroke (width 0.15) (type solid)) (layer "B.Fab"))
    (fp_line (start 0.504 -0.248) (end -0.494 -0.248)
      (stroke (width 0.15) (type solid)) (layer "B.Fab"))
    (fp_line (start 0.504 0.25) (end 0.504 -0.248)
      (stroke (width 0.15) (type solid)) (layer "B.Fab"))
    (pad "1" smd roundrect (at -0.48 0 180) (size 0.59 0.64) (layers "B.Cu" "B.Paste" "B.Mask") (roundrect_rratio 0.25)
      (net 2 "GND") (pintype "passive"))
    (pad "2" smd roundrect (at 0.48 0 180) (size 0.59 0.64) (layers "B.Cu" "B.Paste" "B.Mask") (roundrect_rratio 0.25)
      (net 18 "Net-(U4C-PCKIN)") (pintype "passive"))
  )
)
